(kicad_pcb
	(version 20260206)
	(generator "pcbnew")
	(generator_version "10.0")
	(general
		(thickness 1.6)
		(legacy_teardrops no)
	)
	(paper "A4")
	(title_block
		(title "04192023_DAF0TMB3IC0_F0TG_MB_C_brd_V02_OCP.brd")
		(comment 1 "Grand Teton / footprints 8051-8056 of 8354")
	)
	(layers
		(0 "F.Cu" signal "TOP")
		(4 "In1.Cu" signal "GND")
		(6 "In2.Cu" signal "IN1")
		(8 "In3.Cu" signal "GND1")
		(10 "In4.Cu" signal "IN2")
		(12 "In5.Cu" signal "GND2")
		(14 "In6.Cu" signal "IN3")
		(16 "In7.Cu" signal "GND3")
		(18 "In8.Cu" signal "VCC")
		(20 "In9.Cu" signal "VCC1")
		(22 "In10.Cu" signal "GND4")
		(24 "In11.Cu" signal "IN4")
		(26 "In12.Cu" signal "GND5")
		(28 "In13.Cu" signal "IN5")
		(30 "In14.Cu" signal "GND6")
		(32 "In15.Cu" signal "IN6")
		(34 "In16.Cu" signal "GND7")
		(2 "B.Cu" signal "BOTTOM")
		(9 "F.Adhes" user "F.Adhesive")
		(11 "B.Adhes" user "B.Adhesive")
		(13 "F.Paste" user "Package Geometry/Pastemask Top")
		(15 "B.Paste" user "Package Geometry/Pastemask Bottom")
		(5 "F.SilkS" user "Ref Des/Silkscreen Top")
		(7 "B.SilkS" user "Ref Des/Silkscreen Bottom")
		(1 "F.Mask" user "Board Geometry/Soldermask Top")
		(3 "B.Mask" user "Board Geometry/Soldermask Bottom")
		(17 "Dwgs.User" user "User.Drawings")
		(19 "Cmts.User" user "User.Comments")
		(21 "Eco1.User" user "User.Eco1")
		(23 "Eco2.User" user "User.Eco2")
		(25 "Edge.Cuts" user "Board Geometry/Outline")
		(27 "Margin" user)
		(31 "F.CrtYd" user "Package Geometry/Place Bound Top")
		(29 "B.CrtYd" user "Package Geometry/Place Bound Bottom")
		(35 "F.Fab" user "Ref Des/Assembly Top")
		(33 "B.Fab" user "Ref Des/Assembly Bottom")
	)
	(footprint ""
		(layer "B.Cu")
		(at 153.456386 -315.36005 180)
		(property "Reference" "R572"
			(at 0 0 0)
			(layer "B.SilkS")
			(hide yes)
			(effects
				(font
					(size 1.27 1.27)
				)
				(justify mirror)
			)
		)
		(property "Value" ""
			(at 0 0 0)
			(layer "B.Fab")
			(effects
				(font
					(size 1.27 1.27)
				)
				(justify mirror)
			)
		)
		(duplicate_pad_numbers_are_jumpers no)
		(fp_line
			(start 0.7874 0.4064)
			(end 0.7874 -0.4064)
			(stroke
				(width 0.1524)
				(type default)
			)
			(layer "B.SilkS")
		)
		(fp_line
			(start 0.7874 -0.4064)
			(end -0.7874 -0.4064)
			(stroke
				(width 0.1524)
				(type default)
			)
			(layer "B.SilkS")
		)
		(fp_line
			(start -0.7874 0.4064)
			(end 0.7874 0.4064)
			(stroke
				(width 0.1524)
				(type default)
			)
			(layer "B.SilkS")
		)
		(fp_line
			(start -0.7874 -0.4064)
			(end -0.7874 0.4064)
			(stroke
				(width 0.1524)
				(type default)
			)
			(layer "B.SilkS")
		)
		(fp_line
			(start 0.67945 0.3048)
			(end 0.67945 -0.305054)
			(stroke
				(width 0.1)
				(type default)
			)
			(layer "B.Fab")
		)
		(fp_line
			(start 0.67945 -0.305054)
			(end 0.12065 -0.305054)
			(stroke
				(width 0.1)
				(type default)
			)
			(layer "B.Fab")
		)
		(fp_line
			(start 0.12065 0.3048)
			(end 0.67945 0.3048)
			(stroke
				(width 0.1)
				(type default)
			)
			(layer "B.Fab")
		)
		(fp_line
			(start 0.12065 0.2794)
			(end 0.12065 0.3048)
			(stroke
				(width 0.1)
				(type default)
			)
			(layer "B.Fab")
		)
		(fp_line
			(start 0.12065 -0.2794)
			(end -0.12065 -0.2794)
			(stroke
				(width 0.1)
				(type default)
			)
			(layer "B.Fab")
		)
		(fp_line
			(start 0.12065 -0.305054)
			(end 0.12065 -0.2794)
			(stroke
				(width 0.1)
				(type default)
			)
			(layer "B.Fab")
		)
		(fp_line
			(start -0.120396 0.3048)
			(end -0.120396 0.2794)
			(stroke
				(width 0.1)
				(type default)
			)
			(layer "B.Fab")
		)
		(fp_line
			(start -0.120396 0.2794)
			(end 0.12065 0.2794)
			(stroke
				(width 0.1)
				(type default)
			)
			(layer "B.Fab")
		)
		(fp_line
			(start -0.12065 -0.2794)
			(end -0.12065 -0.3048)
			(stroke
				(width 0.1)
				(type default)
			)
			(layer "B.Fab")
		)
		(fp_line
			(start -0.12065 -0.3048)
			(end -0.67945 -0.3048)
			(stroke
				(width 0.1)
				(type default)
			)
			(layer "B.Fab")
		)
		(fp_line
			(start -0.67945 0.3048)
			(end -0.120396 0.3048)
			(stroke
				(width 0.1)
				(type default)
			)
			(layer "B.Fab")
		)
		(fp_line
			(start -0.67945 -0.3048)
			(end -0.67945 0.3048)
			(stroke
				(width 0.1)
				(type default)
			)
			(layer "B.Fab")
		)
		(pad "1" smd circle
			(at 0.40005 0)
			(size 0 0)
			(layers "B.Cu" "B.Mask" "B.Paste")
			(net "XTAL_CPU1_R_X32K_X1")
		)
		(pad "2" smd circle
			(at -0.40005 0)
			(size 0 0)
			(layers "B.Cu" "B.Mask" "B.Paste")
			(net "XTAL_CPU1_R_X32K_X2")
		)
	)
	(footprint ""
		(layer "B.Cu")
		(at 40.13073 -346.788994 90)
		(property "Reference" "PC632_3"
			(at 0 0 90)
			(layer "B.SilkS")
			(hide yes)
			(effects
				(font
					(size 1.27 1.27)
				)
				(justify mirror)
			)
		)
		(property "Value" ""
			(at 0 0 90)
			(layer "B.Fab")
			(effects
				(font
					(size 1.27 1.27)
				)
				(justify mirror)
			)
		)
		(duplicate_pad_numbers_are_jumpers no)
		(fp_line
			(start 1.524 -0.762)
			(end -1.524 -0.762)
			(stroke
				(width 0.1524)
				(type default)
			)
			(layer "B.SilkS")
		)
		(fp_line
			(start -1.524 -0.762)
			(end -1.524 0.762)
			(stroke
				(width 0.1524)
				(type default)
			)
			(layer "B.SilkS")
		)
		(fp_line
			(start 1.524 0.762)
			(end 1.524 -0.762)
			(stroke
				(width 0.1524)
				(type default)
			)
			(layer "B.SilkS")
		)
		(fp_line
			(start -1.524 0.762)
			(end 1.524 0.762)
			(stroke
				(width 0.1524)
				(type default)
			)
			(layer "B.SilkS")
		)
		(fp_line
			(start 1.1049 -0.724916)
			(end 1.1049 0.724916)
			(stroke
				(width 0.1)
				(type default)
			)
			(layer "B.Fab")
		)
		(fp_line
			(start -1.1049 -0.724916)
			(end 1.1049 -0.724916)
			(stroke
				(width 0.1)
				(type default)
			)
			(layer "B.Fab")
		)
		(fp_line
			(start 1.1049 0.724916)
			(end -1.1049 0.724916)
			(stroke
				(width 0.1)
				(type default)
			)
			(layer "B.Fab")
		)
		(fp_line
			(start -1.1049 0.724916)
			(end -1.1049 -0.724916)
			(stroke
				(width 0.1)
				(type default)
			)
			(layer "B.Fab")
		)
		(pad "1" smd rect
			(at 0.889 0 90)
			(size 1.016 1.27)
			(layers "B.Cu" "B.Mask" "B.Paste")
			(net "SW_P12V_AUX_PVDDIO_P1_FLT")
		)
		(pad "2" smd rect
			(at -0.889 0 90)
			(size 1.016 1.27)
			(layers "B.Cu" "B.Mask" "B.Paste")
			(net "GND")
		)
	)
	(footprint ""
		(layer "B.Cu")
		(at 116.227098 -261.748016 90)
		(property "Reference" "C2271"
			(at 0 0 90)
			(layer "B.SilkS")
			(hide yes)
			(effects
				(font
					(size 1.27 1.27)
				)
				(justify mirror)
			)
		)
		(property "Value" ""
			(at 0 0 90)
			(layer "B.Fab")
			(effects
				(font
					(size 1.27 1.27)
				)
				(justify mirror)
			)
		)
		(duplicate_pad_numbers_are_jumpers no)
		(fp_line
			(start 0.7874 -0.4064)
			(end -0.7874 -0.4064)
			(stroke
				(width 0.1524)
				(type default)
			)
			(layer "B.SilkS")
		)
		(fp_line
			(start -0.7874 -0.4064)
			(end -0.7874 0.4064)
			(stroke
				(width 0.1524)
				(type default)
			)
			(layer "B.SilkS")
		)
		(fp_line
			(start 0.7874 0.4064)
			(end 0.7874 -0.4064)
			(stroke
				(width 0.1524)
				(type default)
			)
			(layer "B.SilkS")
		)
		(fp_line
			(start -0.7874 0.4064)
			(end 0.7874 0.4064)
			(stroke
				(width 0.1524)
				(type default)
			)
			(layer "B.SilkS")
		)
		(fp_line
			(start 0.67945 -0.305054)
			(end 0.12065 -0.305054)
			(stroke
				(width 0.1)
				(type default)
			)
			(layer "B.Fab")
		)
		(fp_line
			(start 0.12065 -0.305054)
			(end 0.12065 -0.2794)
			(stroke
				(width 0.1)
				(type default)
			)
			(layer "B.Fab")
		)
		(fp_line
			(start -0.12065 -0.3048)
			(end -0.67945 -0.3048)
			(stroke
				(width 0.1)
				(type default)
			)
			(layer "B.Fab")
		)
		(fp_line
			(start -0.67945 -0.3048)
			(end -0.67945 0.3048)
			(stroke
				(width 0.1)
				(type default)
			)
			(layer "B.Fab")
		)
		(fp_line
			(start 0.12065 -0.2794)
			(end -0.12065 -0.2794)
			(stroke
				(width 0.1)
				(type default)
			)
			(layer "B.Fab")
		)
		(fp_line
			(start -0.12065 -0.2794)
			(end -0.12065 -0.3048)
			(stroke
				(width 0.1)
				(type default)
			)
			(layer "B.Fab")
		)
		(fp_line
			(start 0.12065 0.2794)
			(end 0.12065 0.3048)
			(stroke
				(width 0.1)
				(type default)
			)
			(layer "B.Fab")
		)
		(fp_line
			(start -0.120396 0.2794)
			(end 0.12065 0.2794)
			(stroke
				(width 0.1)
				(type default)
			)
			(layer "B.Fab")
		)
		(fp_line
			(start 0.67945 0.3048)
			(end 0.67945 -0.305054)
			(stroke
				(width 0.1)
				(type default)
			)
			(layer "B.Fab")
		)
		(fp_line
			(start 0.12065 0.3048)
			(end 0.67945 0.3048)
			(stroke
				(width 0.1)
				(type default)
			)
			(layer "B.Fab")
		)
		(fp_line
			(start -0.120396 0.3048)
			(end -0.120396 0.2794)
			(stroke
				(width 0.1)
				(type default)
			)
			(layer "B.Fab")
		)
		(fp_line
			(start -0.67945 0.3048)
			(end -0.120396 0.3048)
			(stroke
				(width 0.1)
				(type default)
			)
			(layer "B.Fab")
		)
		(pad "1" smd circle
			(at 0.40005 0 270)
			(size 0 0)
			(layers "B.Cu" "B.Mask" "B.Paste")
			(net "PVDD11_S3_P1")
		)
		(pad "2" smd circle
			(at -0.40005 0 270)
			(size 0 0)
			(layers "B.Cu" "B.Mask" "B.Paste")
			(net "GND")
		)
	)
	(footprint ""
		(layer "B.Cu")
		(at 346.71889 -398.942052 90)
		(property "Reference" "C636"
			(at 0 0 90)
			(layer "B.SilkS")
			(hide yes)
			(effects
				(font
					(size 1.27 1.27)
				)
				(justify mirror)
			)
		)
		(property "Value" ""
			(at 0 0 90)
			(layer "B.Fab")
			(effects
				(font
					(size 1.27 1.27)
				)
				(justify mirror)
			)
		)
		(duplicate_pad_numbers_are_jumpers no)
		(fp_line
			(start 0.7874 -0.4064)
			(end -0.7874 -0.4064)
			(stroke
				(width 0.1524)
				(type default)
			)
			(layer "B.SilkS")
		)
		(fp_line
			(start -0.7874 -0.4064)
			(end -0.7874 0.4064)
			(stroke
				(width 0.1524)
				(type default)
			)
			(layer "B.SilkS")
		)
		(fp_line
			(start 0.7874 0.4064)
			(end 0.7874 -0.4064)
			(stroke
				(width 0.1524)
				(type default)
			)
			(layer "B.SilkS")
		)
		(fp_line
			(start -0.7874 0.4064)
			(end 0.7874 0.4064)
			(stroke
				(width 0.1524)
				(type default)
			)
			(layer "B.SilkS")
		)
		(fp_line
			(start 0.67945 -0.305054)
			(end 0.12065 -0.305054)
			(stroke
				(width 0.1)
				(type default)
			)
			(layer "B.Fab")
		)
		(fp_line
			(start 0.12065 -0.305054)
			(end 0.12065 -0.2794)
			(stroke
				(width 0.1)
				(type default)
			)
			(layer "B.Fab")
		)
		(fp_line
			(start -0.12065 -0.3048)
			(end -0.67945 -0.3048)
			(stroke
				(width 0.1)
				(type default)
			)
			(layer "B.Fab")
		)
		(fp_line
			(start -0.67945 -0.3048)
			(end -0.67945 0.3048)
			(stroke
				(width 0.1)
				(type default)
			)
			(layer "B.Fab")
		)
		(fp_line
			(start 0.12065 -0.2794)
			(end -0.12065 -0.2794)
			(stroke
				(width 0.1)
				(type default)
			)
			(layer "B.Fab")
		)
		(fp_line
			(start -0.12065 -0.2794)
			(end -0.12065 -0.3048)
			(stroke
				(width 0.1)
				(type default)
			)
			(layer "B.Fab")
		)
		(fp_line
			(start 0.12065 0.2794)
			(end 0.12065 0.3048)
			(stroke
				(width 0.1)
				(type default)
			)
			(layer "B.Fab")
		)
		(fp_line
			(start -0.120396 0.2794)
			(end 0.12065 0.2794)
			(stroke
				(width 0.1)
				(type default)
			)
			(layer "B.Fab")
		)
		(fp_line
			(start 0.67945 0.3048)
			(end 0.67945 -0.305054)
			(stroke
				(width 0.1)
				(type default)
			)
			(layer "B.Fab")
		)
		(fp_line
			(start 0.12065 0.3048)
			(end 0.67945 0.3048)
			(stroke
				(width 0.1)
				(type default)
			)
			(layer "B.Fab")
		)
		(fp_line
			(start -0.120396 0.3048)
			(end -0.120396 0.2794)
			(stroke
				(width 0.1)
				(type default)
			)
			(layer "B.Fab")
		)
		(fp_line
			(start -0.67945 0.3048)
			(end -0.120396 0.3048)
			(stroke
				(width 0.1)
				(type default)
			)
			(layer "B.Fab")
		)
		(pad "1" smd circle
			(at 0.40005 0 270)
			(size 0 0)
			(layers "B.Cu" "B.Mask" "B.Paste")
			(net "P0V9_CPU0_RT_2D")
		)
		(pad "2" smd circle
			(at -0.40005 0 270)
			(size 0 0)
			(layers "B.Cu" "B.Mask" "B.Paste")
			(net "GND")
		)
	)
	(footprint ""
		(layer "B.Cu")
		(at 132.490972 -41.007792 90)
		(property "Reference" "C6033"
			(at 0 0 90)
			(layer "B.SilkS")
			(hide yes)
			(effects
				(font
					(size 1.27 1.27)
				)
				(justify mirror)
			)
		)
		(property "Value" ""
			(at 0 0 90)
			(layer "B.Fab")
			(effects
				(font
					(size 1.27 1.27)
				)
				(justify mirror)
			)
		)
		(duplicate_pad_numbers_are_jumpers no)
		(fp_line
			(start 0.7874 -0.4064)
			(end -0.7874 -0.4064)
			(stroke
				(width 0.1524)
				(type default)
			)
			(layer "B.SilkS")
		)
		(fp_line
			(start -0.7874 -0.4064)
			(end -0.7874 0.4064)
			(stroke
				(width 0.1524)
				(type default)
			)
			(layer "B.SilkS")
		)
		(fp_line
			(start 0.7874 0.4064)
			(end 0.7874 -0.4064)
			(stroke
				(width 0.1524)
				(type default)
			)
			(layer "B.SilkS")
		)
		(fp_line
			(start -0.7874 0.4064)
			(end 0.7874 0.4064)
			(stroke
				(width 0.1524)
				(type default)
			)
			(layer "B.SilkS")
		)
		(fp_line
			(start 0.67945 -0.305054)
			(end 0.12065 -0.305054)
			(stroke
				(width 0.1)
				(type default)
			)
			(layer "B.Fab")
		)
		(fp_line
			(start 0.12065 -0.305054)
			(end 0.12065 -0.2794)
			(stroke
				(width 0.1)
				(type default)
			)
			(layer "B.Fab")
		)
		(fp_line
			(start -0.12065 -0.3048)
			(end -0.67945 -0.3048)
			(stroke
				(width 0.1)
				(type default)
			)
			(layer "B.Fab")
		)
		(fp_line
			(start -0.67945 -0.3048)
			(end -0.67945 0.3048)
			(stroke
				(width 0.1)
				(type default)
			)
			(layer "B.Fab")
		)
		(fp_line
			(start 0.12065 -0.2794)
			(end -0.12065 -0.2794)
			(stroke
				(width 0.1)
				(type default)
			)
			(layer "B.Fab")
		)
		(fp_line
			(start -0.12065 -0.2794)
			(end -0.12065 -0.3048)
			(stroke
				(width 0.1)
				(type default)
			)
			(layer "B.Fab")
		)
		(fp_line
			(start 0.12065 0.2794)
			(end 0.12065 0.3048)
			(stroke
				(width 0.1)
				(type default)
			)
			(layer "B.Fab")
		)
		(fp_line
			(start -0.120396 0.2794)
			(end 0.12065 0.2794)
			(stroke
				(width 0.1)
				(type default)
			)
			(layer "B.Fab")
		)
		(fp_line
			(start 0.67945 0.3048)
			(end 0.67945 -0.305054)
			(stroke
				(width 0.1)
				(type default)
			)
			(layer "B.Fab")
		)
		(fp_line
			(start 0.12065 0.3048)
			(end 0.67945 0.3048)
			(stroke
				(width 0.1)
				(type default)
			)
			(layer "B.Fab")
		)
		(fp_line
			(start -0.120396 0.3048)
			(end -0.120396 0.2794)
			(stroke
				(width 0.1)
				(type default)
			)
			(layer "B.Fab")
		)
		(fp_line
			(start -0.67945 0.3048)
			(end -0.120396 0.3048)
			(stroke
				(width 0.1)
				(type default)
			)
			(layer "B.Fab")
		)
		(pad "1" smd circle
			(at 0.40005 0 270)
			(size 0 0)
			(layers "B.Cu" "B.Mask" "B.Paste")
			(net "P1V2_CPU0_USB_DVDD12")
		)
		(pad "2" smd circle
			(at -0.40005 0 270)
			(size 0 0)
			(layers "B.Cu" "B.Mask" "B.Paste")
			(net "GND")
		)
	)
	(footprint ""
		(layer "B.Cu")
		(at 236.093 -234.061 -90)
		(property "Reference" "R148"
			(at 0 0 90)
			(layer "B.SilkS")
			(hide yes)
			(effects
				(font
					(size 1.27 1.27)
				)
				(justify mirror)
			)
		)
		(property "Value" ""
			(at 0 0 90)
			(layer "B.Fab")
			(effects
				(font
					(size 1.27 1.27)
				)
				(justify mirror)
			)
		)
		(duplicate_pad_numbers_are_jumpers no)
		(fp_line
			(start -0.7874 0.4064)
			(end 0.7874 0.4064)
			(stroke
				(width 0.1524)
				(type default)
			)
			(layer "B.SilkS")
		)
		(fp_line
			(start 0.7874 0.4064)
			(end 0.7874 -0.4064)
			(stroke
				(width 0.1524)
				(type default)
			)
			(layer "B.SilkS")
		)
		(fp_line
			(start -0.7874 -0.4064)
			(end -0.7874 0.4064)
			(stroke
				(width 0.1524)
				(type default)
			)
			(layer "B.SilkS")
		)
		(fp_line
			(start 0.7874 -0.4064)
			(end -0.7874 -0.4064)
			(stroke
				(width 0.1524)
				(type default)
			)
			(layer "B.SilkS")
		)
		(fp_line
			(start -0.67945 0.3048)
			(end -0.120396 0.3048)
			(stroke
				(width 0.1)
				(type default)
			)
			(layer "B.Fab")
		)
		(fp_line
			(start -0.120396 0.3048)
			(end -0.120396 0.2794)
			(stroke
				(width 0.1)
				(type default)
			)
			(layer "B.Fab")
		)
		(fp_line
			(start 0.12065 0.3048)
			(end 0.67945 0.3048)
			(stroke
				(width 0.1)
				(type default)
			)
			(layer "B.Fab")
		)
		(fp_line
			(start 0.67945 0.3048)
			(end 0.67945 -0.305054)
			(stroke
				(width 0.1)
				(type default)
			)
			(layer "B.Fab")
		)
		(fp_line
			(start -0.120396 0.2794)
			(end 0.12065 0.2794)
			(stroke
				(width 0.1)
				(type default)
			)
			(layer "B.Fab")
		)
		(fp_line
			(start 0.12065 0.2794)
			(end 0.12065 0.3048)
			(stroke
				(width 0.1)
				(type default)
			)
			(layer "B.Fab")
		)
		(fp_line
			(start -0.12065 -0.2794)
			(end -0.12065 -0.3048)
			(stroke
				(width 0.1)
				(type default)
			)
			(layer "B.Fab")
		)
		(fp_line
			(start 0.12065 -0.2794)
			(end -0.12065 -0.2794)
			(stroke
				(width 0.1)
				(type default)
			)
			(layer "B.Fab")
		)
		(fp_line
			(start -0.67945 -0.3048)
			(end -0.67945 0.3048)
			(stroke
				(width 0.1)
				(type default)
			)
			(layer "B.Fab")
		)
		(fp_line
			(start -0.12065 -0.3048)
			(end -0.67945 -0.3048)
			(stroke
				(width 0.1)
				(type default)
			)
			(layer "B.Fab")
		)
		(fp_line
			(start 0.12065 -0.305054)
			(end 0.12065 -0.2794)
			(stroke
				(width 0.1)
				(type default)
			)
			(layer "B.Fab")
		)
		(fp_line
			(start 0.67945 -0.305054)
			(end 0.12065 -0.305054)
			(stroke
				(width 0.1)
				(type default)
			)
			(layer "B.Fab")
		)
		(pad "1" smd circle
			(at 0.40005 0 90)
			(size 0 0)
			(layers "B.Cu" "B.Mask" "B.Paste")
			(net "SMB_CPU0_CPU1_SEC_SDA_R2")
		)
		(pad "2" smd circle
			(at -0.40005 0 90)
			(size 0 0)
			(layers "B.Cu" "B.Mask" "B.Paste")
			(net "SMB_CPU1_SEC_R_SDA")
		)
	)
)
